(kicad_pcb
	(version 20211014)
	(generator pcbnew)
	(general
    (thickness 1.6)
  )
	(paper "A4")
	(title_block
    (title "SA800U (Snapdragon 845) Baseboard")
    (date "2023-10-19")
    (rev "1.0.3")
    (company "Antmicro Ltd.")
    (comment 1 "www.antmicro.com")
		(comment 9 "footprints 341-350 of 589")
	)
	(layers
    (0 "F.Cu" signal)
    (1 "In1.Cu" power)
    (2 "In2.Cu" signal)
    (3 "In3.Cu" signal)
    (4 "In4.Cu" power)
    (31 "B.Cu" signal)
    (32 "B.Adhes" user "B.Adhesive")
    (33 "F.Adhes" user "F.Adhesive")
    (34 "B.Paste" user)
    (35 "F.Paste" user)
    (36 "B.SilkS" user "B.Silkscreen")
    (37 "F.SilkS" user "F.Silkscreen")
    (38 "B.Mask" user)
    (39 "F.Mask" user)
    (40 "Dwgs.User" user "User.Drawings")
    (41 "Cmts.User" user "User.Comments")
    (42 "Eco1.User" user "User.Eco1")
    (43 "Eco2.User" user "User.Eco2")
    (44 "Edge.Cuts" user)
    (45 "Margin" user)
    (46 "B.CrtYd" user "B.Courtyard")
    (47 "F.CrtYd" user "F.Courtyard")
    (48 "B.Fab" user)
    (49 "F.Fab" user)
  )
	(footprint "sa800u-baseboard-hw-footprints:R_0402_1005Metric" (layer "B.Cu")
    (tedit 5FD9C158)
    (at 139.388164 128.712953 90)
    (descr "Resistor SMD 0402")
    (tags "resistor SMD 0402")
    (property "Author" "Antmicro")
    (property "License" "Apache-2.0")
    (property "MPN" "CR0402-FX-2002GLF")
    (property "Manufacturer" "Bourns")
    (property "Sheetfile" "hdmi-converter.kicad_sch")
    (property "Sheetname" "HDMI converter")
    (property "Tolerance" "1%")
    (property "Val" "20k")
    (attr smd)
    (fp_text reference "R27" (at -0.291 -2.64 270) (layer "B.SilkS")
      (effects (font (size 0.7 0.7) (thickness 0.15)) (justify left bottom mirror))
    )
    (fp_text value "R_20k_0402" (at 0 -1.4 270) (layer "B.Fab")
      (effects (font (size 0.7 0.7) (thickness 0.15)) (justify left bottom mirror))
    )
    (fp_text user "${REFERENCE}" (at -0.95 -3.168 270) (layer "B.Fab") hide
      (effects (font (size 0.7 0.7) (thickness 0.15)) (justify left bottom mirror))
    )
    (fp_text user "License: Apache-2.0" (at -0.95 -5.169 270) (layer "B.Fab") hide
      (effects (font (size 0.7 0.7) (thickness 0.15)) (justify left bottom mirror))
    )
    (fp_text user "Author: Antmicro" (at -0.95 -4.169 270) (layer "B.Fab") hide
      (effects (font (size 0.7 0.7) (thickness 0.15)) (justify left bottom mirror))
    )
    (fp_rect (start -0.93 0.47) (end 0.93 -0.47) (layer "B.CrtYd") (width 0.05) (fill none))
    (fp_rect (start -0.5 0.25) (end 0.5 -0.25) (layer "B.Fab") (width 0.15) (fill none))
    (pad "1" smd roundrect (at -0.485 0 90) (size 0.59 0.64) (layers "B.Cu" "B.Paste" "B.Mask") (roundrect_rratio 0.25)
      (net 395 "Net-(R27-Pad1)") (pintype "passive"))
    (pad "2" smd roundrect (at 0.485 0 90) (size 0.59 0.64) (layers "B.Cu" "B.Paste" "B.Mask") (roundrect_rratio 0.25)
      (net 1 "GND") (pintype "passive"))
  )
	(footprint "sa800u-baseboard-hw-footprints:C_0402_1005Metric" (layer "B.Cu")
    (tedit 616D63CF)
    (at 137.39 128.71 90)
    (descr "Capacitor SMD 0402")
    (tags "capacitor SMD 0402")
    (property "Author" "Antmicro")
    (property "DNP" "DNP")
    (property "Dielectric" "")
    (property "License" "Apache-2.0")
    (property "MPN" "CC0402MRX5R5BB106")
    (property "Manufacturer" "Yaego")
    (property "Sheetfile" "hdmi-converter.kicad_sch")
    (property "Sheetname" "HDMI converter")
    (property "Val" "10u")
    (property "Voltage" "")
    (attr exclude_from_pos_files)
    (fp_text reference "C23" (at -0.29 -2.64 270) (layer "B.SilkS")
      (effects (font (size 0.7 0.7) (thickness 0.15)) (justify left bottom mirror))
    )
    (fp_text value "C_10u_0402" (at 0 -1.4 270) (layer "B.Fab")
      (effects (font (size 0.7 0.7) (thickness 0.15)) (justify left bottom mirror))
    )
    (fp_text user "License: Apache-2.0" (at -0.932 -5.17 270) (layer "B.Fab") hide
      (effects (font (size 0.7 0.7) (thickness 0.15)) (justify left bottom mirror))
    )
    (fp_text user "Author: Antmicro" (at -0.932 -4.17 270) (layer "B.Fab") hide
      (effects (font (size 0.7 0.7) (thickness 0.15)) (justify left bottom mirror))
    )
    (fp_text user "${REFERENCE}" (at -0.932 -3.168 270) (layer "B.Fab") hide
      (effects (font (size 0.7 0.7) (thickness 0.15)) (justify left bottom mirror))
    )
    (fp_rect (start -0.94 0.47) (end 0.94 -0.47) (layer "B.CrtYd") (width 0.05) (fill none))
    (fp_rect (start -0.499 0.249) (end 0.499 -0.249) (layer "B.Fab") (width 0.15) (fill none))
    (pad "1" smd roundrect (at -0.484 0 90) (size 0.59 0.64) (layers "B.Cu" "B.Paste" "B.Mask") (roundrect_rratio 0.25)
      (net 184 "/HDMI converter/LT9611_VCC33_IO") (pintype "passive"))
    (pad "2" smd roundrect (at 0.484 0 90) (size 0.59 0.64) (layers "B.Cu" "B.Paste" "B.Mask") (roundrect_rratio 0.25)
      (net 1 "GND") (pintype "passive"))
  )
	(footprint "sa800u-baseboard-hw-footprints:C_0402_1005Metric" (layer "B.Cu")
    (tedit 616D63CF)
    (at 137.773164 126.212952)
    (descr "Capacitor SMD 0402")
    (tags "capacitor SMD 0402")
    (property "Author" "Antmicro")
    (property "Dielectric" "X5R")
    (property "License" "Apache-2.0")
    (property "MPN" "GRM155R61H104KE14D")
    (property "Manufacturer" "Murata")
    (property "Sheetfile" "hdmi-converter.kicad_sch")
    (property "Sheetname" "HDMI converter")
    (property "Val" "100n")
    (property "Voltage" "50V")
    (attr smd)
    (fp_text reference "C29" (at 0.666836 1.327048 180) (layer "B.SilkS")
      (effects (font (size 0.7 0.7) (thickness 0.15)) (justify left bottom mirror))
    )
    (fp_text value "C_100n_0402" (at 0 -1.4 180) (layer "B.Fab")
      (effects (font (size 0.7 0.7) (thickness 0.15)) (justify left bottom mirror))
    )
    (fp_text user "Author: Antmicro" (at -0.932 -4.17 180) (layer "B.Fab") hide
      (effects (font (size 0.7 0.7) (thickness 0.15)) (justify left bottom mirror))
    )
    (fp_text user "${REFERENCE}" (at -0.932 -3.168 180) (layer "B.Fab") hide
      (effects (font (size 0.7 0.7) (thickness 0.15)) (justify left bottom mirror))
    )
    (fp_text user "License: Apache-2.0" (at -0.932 -5.17 180) (layer "B.Fab") hide
      (effects (font (size 0.7 0.7) (thickness 0.15)) (justify left bottom mirror))
    )
    (fp_rect (start -0.94 0.47) (end 0.94 -0.47) (layer "B.CrtYd") (width 0.05) (fill none))
    (fp_rect (start -0.499 0.249) (end 0.499 -0.249) (layer "B.Fab") (width 0.15) (fill none))
    (pad "1" smd roundrect (at -0.484 0) (size 0.59 0.64) (layers "B.Cu" "B.Paste" "B.Mask") (roundrect_rratio 0.25)
      (net 184 "/HDMI converter/LT9611_VCC33_IO") (pintype "passive"))
    (pad "2" smd roundrect (at 0.484 0) (size 0.59 0.64) (layers "B.Cu" "B.Paste" "B.Mask") (roundrect_rratio 0.25)
      (net 1 "GND") (pintype "passive"))
  )
	(footprint "sa800u-baseboard-hw-footprints:C_0402_1005Metric" (layer "B.Cu")
    (tedit 616D63CF)
    (at 138.388164 128.712953 90)
    (descr "Capacitor SMD 0402")
    (tags "capacitor SMD 0402")
    (property "Author" "Antmicro")
    (property "Dielectric" "X5R")
    (property "License" "Apache-2.0")
    (property "MPN" "GRM155R61H104KE14D")
    (property "Manufacturer" "Murata")
    (property "Sheetfile" "hdmi-converter.kicad_sch")
    (property "Sheetname" "HDMI converter")
    (property "Val" "100n")
    (property "Voltage" "50V")
    (attr smd)
    (fp_text reference "C32" (at -0.29 -2.64 270) (layer "B.SilkS")
      (effects (font (size 0.7 0.7) (thickness 0.15)) (justify left bottom mirror))
    )
    (fp_text value "C_100n_0402" (at 0 -1.4 270) (layer "B.Fab")
      (effects (font (size 0.7 0.7) (thickness 0.15)) (justify left bottom mirror))
    )
    (fp_text user "License: Apache-2.0" (at -0.932 -5.17 270) (layer "B.Fab") hide
      (effects (font (size 0.7 0.7) (thickness 0.15)) (justify left bottom mirror))
    )
    (fp_text user "Author: Antmicro" (at -0.932 -4.17 270) (layer "B.Fab") hide
      (effects (font (size 0.7 0.7) (thickness 0.15)) (justify left bottom mirror))
    )
    (fp_text user "${REFERENCE}" (at -0.932 -3.168 270) (layer "B.Fab") hide
      (effects (font (size 0.7 0.7) (thickness 0.15)) (justify left bottom mirror))
    )
    (fp_rect (start -0.94 0.47) (end 0.94 -0.47) (layer "B.CrtYd") (width 0.05) (fill none))
    (fp_rect (start -0.499 0.249) (end 0.499 -0.249) (layer "B.Fab") (width 0.15) (fill none))
    (pad "1" smd roundrect (at -0.484 0 90) (size 0.59 0.64) (layers "B.Cu" "B.Paste" "B.Mask") (roundrect_rratio 0.25)
      (net 184 "/HDMI converter/LT9611_VCC33_IO") (pintype "passive"))
    (pad "2" smd roundrect (at 0.484 0 90) (size 0.59 0.64) (layers "B.Cu" "B.Paste" "B.Mask") (roundrect_rratio 0.25)
      (net 1 "GND") (pintype "passive"))
  )
	(footprint "sa800u-baseboard-hw-footprints:C_0402_1005Metric" (layer "B.Cu")
    (tedit 616D63CF)
    (at 144.6 122.9 180)
    (descr "Capacitor SMD 0402")
    (tags "capacitor SMD 0402")
    (property "Author" "Antmicro")
    (property "DNP" "DNP")
    (property "Dielectric" "")
    (property "License" "Apache-2.0")
    (property "MPN" "CC0402MRX5R5BB106")
    (property "Manufacturer" "Yaego")
    (property "Sheetfile" "hdmi-converter.kicad_sch")
    (property "Sheetname" "HDMI converter")
    (property "Val" "10u")
    (property "Voltage" "")
    (attr exclude_from_pos_files)
    (fp_text reference "C38" (at -1 -1.18) (layer "B.SilkS")
      (effects (font (size 0.7 0.7) (thickness 0.15)) (justify left bottom mirror))
    )
    (fp_text value "C_10u_0402" (at 0 -1.4) (layer "B.Fab")
      (effects (font (size 0.7 0.7) (thickness 0.15)) (justify left bottom mirror))
    )
    (fp_text user "License: Apache-2.0" (at -0.932 -5.17) (layer "B.Fab") hide
      (effects (font (size 0.7 0.7) (thickness 0.15)) (justify left bottom mirror))
    )
    (fp_text user "${REFERENCE}" (at -0.932 -3.168) (layer "B.Fab") hide
      (effects (font (size 0.7 0.7) (thickness 0.15)) (justify left bottom mirror))
    )
    (fp_text user "Author: Antmicro" (at -0.932 -4.17) (layer "B.Fab") hide
      (effects (font (size 0.7 0.7) (thickness 0.15)) (justify left bottom mirror))
    )
    (fp_rect (start -0.94 0.47) (end 0.94 -0.47) (layer "B.CrtYd") (width 0.05) (fill none))
    (fp_rect (start -0.499 0.249) (end 0.499 -0.249) (layer "B.Fab") (width 0.15) (fill none))
    (pad "1" smd roundrect (at -0.484 0 180) (size 0.59 0.64) (layers "B.Cu" "B.Paste" "B.Mask") (roundrect_rratio 0.25)
      (net 185 "/HDMI converter/LT9611_VCC33_RX") (pintype "passive"))
    (pad "2" smd roundrect (at 0.484 0 180) (size 0.59 0.64) (layers "B.Cu" "B.Paste" "B.Mask") (roundrect_rratio 0.25)
      (net 1 "GND") (pintype "passive"))
  )
	(footprint "sa800u-baseboard-hw-footprints:C_0402_1005Metric" (layer "B.Cu")
    (tedit 616D63CF)
    (at 144.1 129.15 180)
    (descr "Capacitor SMD 0402")
    (tags "capacitor SMD 0402")
    (property "Author" "Antmicro")
    (property "Dielectric" "X5R")
    (property "License" "Apache-2.0")
    (property "MPN" "GRM155R61H104KE14D")
    (property "Manufacturer" "Murata")
    (property "Sheetfile" "hdmi-converter.kicad_sch")
    (property "Sheetname" "HDMI converter")
    (property "Val" "100n")
    (property "Voltage" "50V")
    (attr smd)
    (fp_text reference "C42" (at -3.119 -0.3) (layer "B.SilkS")
      (effects (font (size 0.7 0.7) (thickness 0.15)) (justify left bottom mirror))
    )
    (fp_text value "C_100n_0402" (at 0 -1.4) (layer "B.Fab")
      (effects (font (size 0.7 0.7) (thickness 0.15)) (justify left bottom mirror))
    )
    (fp_text user "License: Apache-2.0" (at -0.932 -5.17) (layer "B.Fab") hide
      (effects (font (size 0.7 0.7) (thickness 0.15)) (justify left bottom mirror))
    )
    (fp_text user "${REFERENCE}" (at -0.932 -3.168) (layer "B.Fab") hide
      (effects (font (size 0.7 0.7) (thickness 0.15)) (justify left bottom mirror))
    )
    (fp_text user "Author: Antmicro" (at -0.932 -4.17) (layer "B.Fab") hide
      (effects (font (size 0.7 0.7) (thickness 0.15)) (justify left bottom mirror))
    )
    (fp_rect (start -0.94 0.47) (end 0.94 -0.47) (layer "B.CrtYd") (width 0.05) (fill none))
    (fp_rect (start -0.499 0.249) (end 0.499 -0.249) (layer "B.Fab") (width 0.15) (fill none))
    (pad "1" smd roundrect (at -0.484 0 180) (size 0.59 0.64) (layers "B.Cu" "B.Paste" "B.Mask") (roundrect_rratio 0.25)
      (net 185 "/HDMI converter/LT9611_VCC33_RX") (pintype "passive"))
    (pad "2" smd roundrect (at 0.484 0 180) (size 0.59 0.64) (layers "B.Cu" "B.Paste" "B.Mask") (roundrect_rratio 0.25)
      (net 1 "GND") (pintype "passive"))
  )
	(footprint "sa800u-baseboard-hw-footprints:C_0402_1005Metric" (layer "B.Cu")
    (tedit 616D63CF)
    (at 140.85 131.95 180)
    (descr "Capacitor SMD 0402")
    (tags "capacitor SMD 0402")
    (property "Author" "Antmicro")
    (property "DNP" "DNP")
    (property "Dielectric" "")
    (property "License" "Apache-2.0")
    (property "MPN" "CC0402MRX5R5BB106")
    (property "Manufacturer" "Yaego")
    (property "Sheetfile" "hdmi-converter.kicad_sch")
    (property "Sheetname" "HDMI converter")
    (property "Val" "10u")
    (property "Voltage" "")
    (attr exclude_from_pos_files)
    (fp_text reference "C43" (at 0.89 -0.41) (layer "B.SilkS")
      (effects (font (size 0.7 0.7) (thickness 0.15)) (justify left bottom mirror))
    )
    (fp_text value "C_10u_0402" (at 0 -1.4) (layer "B.Fab")
      (effects (font (size 0.7 0.7) (thickness 0.15)) (justify left bottom mirror))
    )
    (fp_text user "Author: Antmicro" (at -0.932 -4.17) (layer "B.Fab") hide
      (effects (font (size 0.7 0.7) (thickness 0.15)) (justify left bottom mirror))
    )
    (fp_text user "${REFERENCE}" (at -0.932 -3.168) (layer "B.Fab") hide
      (effects (font (size 0.7 0.7) (thickness 0.15)) (justify left bottom mirror))
    )
    (fp_text user "License: Apache-2.0" (at -0.932 -5.17) (layer "B.Fab") hide
      (effects (font (size 0.7 0.7) (thickness 0.15)) (justify left bottom mirror))
    )
    (fp_rect (start -0.94 0.47) (end 0.94 -0.47) (layer "B.CrtYd") (width 0.05) (fill none))
    (fp_rect (start -0.499 0.249) (end 0.499 -0.249) (layer "B.Fab") (width 0.15) (fill none))
    (pad "1" smd roundrect (at -0.484 0 180) (size 0.59 0.64) (layers "B.Cu" "B.Paste" "B.Mask") (roundrect_rratio 0.25)
      (net 187 "/HDMI converter/LT9611_VCC33_TX") (pintype "passive"))
    (pad "2" smd roundrect (at 0.484 0 180) (size 0.59 0.64) (layers "B.Cu" "B.Paste" "B.Mask") (roundrect_rratio 0.25)
      (net 1 "GND") (pintype "passive"))
  )
	(footprint "sa800u-baseboard-hw-footprints:C_0402_1005Metric" (layer "B.Cu")
    (tedit 616D63CF)
    (at 141.65 128.7 90)
    (descr "Capacitor SMD 0402")
    (tags "capacitor SMD 0402")
    (property "Author" "Antmicro")
    (property "Dielectric" "X5R")
    (property "License" "Apache-2.0")
    (property "MPN" "GRM155R61H104KE14D")
    (property "Manufacturer" "Murata")
    (property "Sheetfile" "hdmi-converter.kicad_sch")
    (property "Sheetname" "HDMI converter")
    (property "Val" "100n")
    (property "Voltage" "50V")
    (attr smd)
    (fp_text reference "C45" (at 1.12 -0.65 270) (layer "B.SilkS")
      (effects (font (size 0.7 0.7) (thickness 0.15)) (justify left bottom mirror))
    )
    (fp_text value "C_100n_0402" (at 0 -1.4 270) (layer "B.Fab")
      (effects (font (size 0.7 0.7) (thickness 0.15)) (justify left bottom mirror))
    )
    (fp_text user "Author: Antmicro" (at -0.932 -4.17 270) (layer "B.Fab") hide
      (effects (font (size 0.7 0.7) (thickness 0.15)) (justify left bottom mirror))
    )
    (fp_text user "License: Apache-2.0" (at -0.932 -5.17 270) (layer "B.Fab") hide
      (effects (font (size 0.7 0.7) (thickness 0.15)) (justify left bottom mirror))
    )
    (fp_text user "${REFERENCE}" (at -0.932 -3.168 270) (layer "B.Fab") hide
      (effects (font (size 0.7 0.7) (thickness 0.15)) (justify left bottom mirror))
    )
    (fp_rect (start -0.94 0.47) (end 0.94 -0.47) (layer "B.CrtYd") (width 0.05) (fill none))
    (fp_rect (start -0.499 0.249) (end 0.499 -0.249) (layer "B.Fab") (width 0.15) (fill none))
    (pad "1" smd roundrect (at -0.484 0 90) (size 0.59 0.64) (layers "B.Cu" "B.Paste" "B.Mask") (roundrect_rratio 0.25)
      (net 187 "/HDMI converter/LT9611_VCC33_TX") (pintype "passive"))
    (pad "2" smd roundrect (at 0.484 0 90) (size 0.59 0.64) (layers "B.Cu" "B.Paste" "B.Mask") (roundrect_rratio 0.25)
      (net 1 "GND") (pintype "passive"))
  )
	(footprint "sa800u-baseboard-hw-footprints:C_0402_1005Metric" (layer "B.Cu")
    (tedit 616D63CF)
    (at 138.4 121.7 -90)
    (descr "Capacitor SMD 0402")
    (tags "capacitor SMD 0402")
    (property "Author" "Antmicro")
    (property "Dielectric" "X5R")
    (property "License" "Apache-2.0")
    (property "MPN" "GRM155R61H104KE14D")
    (property "Manufacturer" "Murata")
    (property "Sheetfile" "hdmi-converter.kicad_sch")
    (property "Sheetname" "HDMI converter")
    (property "Val" "100n")
    (property "Voltage" "50V")
    (attr smd)
    (fp_text reference "C28" (at -3.02 -0.36 90) (layer "B.SilkS")
      (effects (font (size 0.7 0.7) (thickness 0.15)) (justify left bottom mirror))
    )
    (fp_text value "C_100n_0402" (at 0 -1.4 90) (layer "B.Fab")
      (effects (font (size 0.7 0.7) (thickness 0.15)) (justify left bottom mirror))
    )
    (fp_text user "Author: Antmicro" (at -0.932 -4.17 90) (layer "B.Fab") hide
      (effects (font (size 0.7 0.7) (thickness 0.15)) (justify left bottom mirror))
    )
    (fp_text user "License: Apache-2.0" (at -0.932 -5.17 90) (layer "B.Fab") hide
      (effects (font (size 0.7 0.7) (thickness 0.15)) (justify left bottom mirror))
    )
    (fp_text user "${REFERENCE}" (at -0.932 -3.168 90) (layer "B.Fab") hide
      (effects (font (size 0.7 0.7) (thickness 0.15)) (justify left bottom mirror))
    )
    (fp_rect (start -0.94 0.47) (end 0.94 -0.47) (layer "B.CrtYd") (width 0.05) (fill none))
    (fp_rect (start -0.499 0.249) (end 0.499 -0.249) (layer "B.Fab") (width 0.15) (fill none))
    (pad "1" smd roundrect (at -0.484 0 270) (size 0.59 0.64) (layers "B.Cu" "B.Paste" "B.Mask") (roundrect_rratio 0.25)
      (net 188 "/HDMI converter/LT9611_VDD12") (pintype "passive"))
    (pad "2" smd roundrect (at 0.484 0 270) (size 0.59 0.64) (layers "B.Cu" "B.Paste" "B.Mask") (roundrect_rratio 0.25)
      (net 1 "GND") (pintype "passive"))
  )
	(footprint "sa800u-baseboard-hw-footprints:C_0402_1005Metric" (layer "B.Cu")
    (tedit 616D63CF)
    (at 139.4 121.7 -90)
    (descr "Capacitor SMD 0402")
    (tags "capacitor SMD 0402")
    (property "Author" "Antmicro")
    (property "Dielectric" "X5R")
    (property "License" "Apache-2.0")
    (property "MPN" "GRM155R61H104KE14D")
    (property "Manufacturer" "Murata")
    (property "Sheetfile" "hdmi-converter.kicad_sch")
    (property "Sheetname" "HDMI converter")
    (property "Val" "100n")
    (property "Voltage" "50V")
    (attr smd)
    (fp_text reference "C31" (at -3.02 -0.36 90) (layer "B.SilkS")
      (effects (font (size 0.7 0.7) (thickness 0.15)) (justify left bottom mirror))
    )
    (fp_text value "C_100n_0402" (at 0 -1.4 90) (layer "B.Fab")
      (effects (font (size 0.7 0.7) (thickness 0.15)) (justify left bottom mirror))
    )
    (fp_text user "License: Apache-2.0" (at -0.932 -5.17 90) (layer "B.Fab") hide
      (effects (font (size 0.7 0.7) (thickness 0.15)) (justify left bottom mirror))
    )
    (fp_text user "${REFERENCE}" (at -0.932 -3.168 90) (layer "B.Fab") hide
      (effects (font (size 0.7 0.7) (thickness 0.15)) (justify left bottom mirror))
    )
    (fp_text user "Author: Antmicro" (at -0.932 -4.17 90) (layer "B.Fab") hide
      (effects (font (size 0.7 0.7) (thickness 0.15)) (justify left bottom mirror))
    )
    (fp_rect (start -0.94 0.47) (end 0.94 -0.47) (layer "B.CrtYd") (width 0.05) (fill none))
    (fp_rect (start -0.499 0.249) (end 0.499 -0.249) (layer "B.Fab") (width 0.15) (fill none))
    (pad "1" smd roundrect (at -0.484 0 270) (size 0.59 0.64) (layers "B.Cu" "B.Paste" "B.Mask") (roundrect_rratio 0.25)
      (net 188 "/HDMI converter/LT9611_VDD12") (pintype "passive"))
    (pad "2" smd roundrect (at 0.484 0 270) (size 0.59 0.64) (layers "B.Cu" "B.Paste" "B.Mask") (roundrect_rratio 0.25)
      (net 1 "GND") (pintype "passive"))
  )
)
